G04 ================== begin FILE IDENTIFICATION RECORD ==================*
G04 Layout Name:  17301-sa.brd*
G04 Film Name:    DP_REF_L6*
G04 File Format:  Gerber RS274X*
G04 File Origin:  Cadence Allegro 16.6-2015-S079*
G04 Origin Date:  Thu Jun 22 17:50:11 2017*
G04 *
G04 Layer:  BOARD GEOMETRY/PANEL_OUTLINE*
G04 Layer:  BOARD GEOMETRY/DP_REF_L6_TBL*
G04 Layer:  BOARD GEOMETRY/DP_REF_L6_BOTTOM*
G04 *
G04 Offset:    (0.00 0.00)*
G04 Mirror:    No*
G04 Mode:      Positive*
G04 Rotation:  0*
G04 FullContactRelief:  No*
G04 UndefLineWidth:     6.00*
G04 ================== end FILE IDENTIFICATION RECORD ====================*
%FSLAX35Y35*MOIN*%
%IR0*IPPOS*OFA0.00000B0.00000*MIA0B0*SFA1.00000B1.00000*%
%ADD10C,.02*%
%ADD11C,.006*%
%ADD12C,.0084*%
G75*
%LPD*%
G75*
G54D10*
G01X615261Y627846D02*
X1350261D01*
G01X615261Y697146D02*
Y627846D01*
G01Y662496D02*
X1350261D01*
G01X615261Y697146D02*
X1350261D01*
G01X790261D02*
Y627846D01*
G01X1035261Y697146D02*
Y627846D01*
G01X1140261Y697146D02*
Y627846D01*
G01X1350261Y697146D02*
Y627846D01*
G54D11*
G01X-19340Y-32800D02*
Y-50300D01*
G01X-24362Y-32800D02*
X-14318D01*
G01X-5552Y-50300D02*
Y-32800D01*
G01Y-41258D02*
X-4460Y-39800D01*
X-3368Y-38925D01*
X-1622Y-38634D01*
X-312Y-38925D01*
X1217Y-40092D01*
X1872Y-41842D01*
Y-50300D01*
G01X15660Y-38634D02*
Y-50300D01*
G01Y-33967D02*
X15223Y-33675D01*
Y-33092D01*
X15660Y-32800D01*
X16097Y-33092D01*
Y-33675D01*
X15660Y-33967D01*
G01X29885Y-48259D02*
X30977Y-49425D01*
X32505Y-50300D01*
X33815D01*
X35125Y-49717D01*
X35998Y-48842D01*
X36435Y-47676D01*
X36217Y-45925D01*
X35343Y-45050D01*
X31413Y-43300D01*
X30540Y-41258D01*
X30977Y-39800D01*
X31850Y-38925D01*
X33160Y-38634D01*
X34470Y-38925D01*
X35780Y-39800D01*
G01X65103Y-54675D02*
X66632Y-55842D01*
X68378Y-56133D01*
X69906Y-55842D01*
X71217Y-54384D01*
X72090Y-52342D01*
Y-38634D01*
G01Y-40967D02*
X71217Y-39800D01*
X69906Y-38925D01*
X68378Y-38634D01*
X66632Y-39217D01*
X65540Y-40383D01*
X64666Y-42425D01*
X64230Y-44467D01*
X64448Y-46217D01*
X65322Y-48259D01*
X66632Y-49717D01*
X68378Y-50300D01*
X69688Y-50008D01*
X71217Y-48842D01*
X72090Y-47676D01*
G01X82385Y-42425D02*
X89372D01*
X88717Y-40383D01*
X87625Y-39217D01*
X86097Y-38634D01*
X84568Y-38925D01*
X83258Y-39800D01*
X82385Y-41842D01*
X81948Y-43592D01*
Y-45342D01*
X82385Y-47092D01*
X83477Y-48842D01*
X84787Y-50008D01*
X86315Y-50300D01*
X87843Y-49717D01*
X89372Y-47967D01*
G01X100103Y-50300D02*
Y-38634D01*
G01Y-40967D02*
X101195Y-39800D01*
X102287Y-38925D01*
X103815Y-38634D01*
X104906Y-38925D01*
X106217Y-39800D01*
G01X116730Y-50300D02*
Y-32800D01*
G01Y-41550D02*
X117822Y-39800D01*
X119132Y-38925D01*
X120442Y-38634D01*
X122406Y-39217D01*
X123717Y-40383D01*
X124590Y-42425D01*
Y-44758D01*
X124153Y-47092D01*
X123280Y-48842D01*
X121752Y-50008D01*
X120442Y-50300D01*
X119132Y-50008D01*
X117822Y-49134D01*
X116730Y-47676D01*
G01X134885Y-42425D02*
X141872D01*
X141217Y-40383D01*
X140125Y-39217D01*
X138597Y-38634D01*
X137068Y-38925D01*
X135758Y-39800D01*
X134885Y-41842D01*
X134448Y-43592D01*
Y-45342D01*
X134885Y-47092D01*
X135977Y-48842D01*
X137287Y-50008D01*
X138815Y-50300D01*
X140343Y-49717D01*
X141872Y-47967D01*
G01X152603Y-50300D02*
Y-38634D01*
G01Y-40967D02*
X153695Y-39800D01*
X154787Y-38925D01*
X156315Y-38634D01*
X157406Y-38925D01*
X158717Y-39800D01*
G01X190660Y-38634D02*
Y-50300D01*
G01Y-33967D02*
X190223Y-33675D01*
Y-33092D01*
X190660Y-32800D01*
X191097Y-33092D01*
Y-33675D01*
X190660Y-33967D01*
G01X204885Y-48259D02*
X205977Y-49425D01*
X207505Y-50300D01*
X208815D01*
X210125Y-49717D01*
X210998Y-48842D01*
X211435Y-47676D01*
X211217Y-45925D01*
X210343Y-45050D01*
X206413Y-43300D01*
X205540Y-41258D01*
X205977Y-39800D01*
X206850Y-38925D01*
X208160Y-38634D01*
X209470Y-38925D01*
X210780Y-39800D01*
G01X239666Y-54675D02*
X241195Y-55842D01*
X242505Y-56133D01*
X244252Y-55550D01*
X245562Y-54092D01*
X246217Y-51466D01*
Y-38634D01*
G01Y-33967D02*
X245780Y-33675D01*
Y-33092D01*
X246217Y-32800D01*
X246653Y-33092D01*
Y-33675D01*
X246217Y-33967D01*
G01X256948Y-38634D02*
Y-46800D01*
X257822Y-48842D01*
X259132Y-50008D01*
X260660Y-50300D01*
X262188Y-50008D01*
X263498Y-48842D01*
X264372Y-46800D01*
G01Y-50300D02*
Y-38634D01*
G01X274885Y-48259D02*
X275977Y-49425D01*
X277505Y-50300D01*
X278815D01*
X280125Y-49717D01*
X280998Y-48842D01*
X281435Y-47676D01*
X281217Y-45925D01*
X280343Y-45050D01*
X276413Y-43300D01*
X275540Y-41258D01*
X275977Y-39800D01*
X276850Y-38925D01*
X278160Y-38634D01*
X279470Y-38925D01*
X280780Y-39800D01*
G01X295660Y-32800D02*
Y-50300D01*
G01X292603Y-38634D02*
X298717D01*
G01X329350Y-50300D02*
Y-35425D01*
X329787Y-33967D01*
X330660Y-33092D01*
X331970Y-32800D01*
X333280Y-33383D01*
X333935Y-34842D01*
G01X331315Y-39800D02*
X326948D01*
G01X348160Y-50300D02*
X346850Y-50008D01*
X345540Y-48842D01*
X344666Y-46800D01*
X344230Y-44467D01*
X344666Y-42133D01*
X345540Y-40092D01*
X346850Y-38925D01*
X348160Y-38634D01*
X349470Y-38925D01*
X350780Y-40092D01*
X351653Y-42133D01*
X351872Y-44467D01*
X351653Y-46800D01*
X350780Y-48842D01*
X349470Y-50008D01*
X348160Y-50300D01*
G01X362603D02*
Y-38634D01*
G01Y-40967D02*
X363695Y-39800D01*
X364787Y-38925D01*
X366315Y-38634D01*
X367406Y-38925D01*
X368717Y-39800D01*
G01X396075Y-55550D02*
X397385Y-56133D01*
X399132Y-55550D01*
X400223Y-54384D01*
X401097Y-52925D01*
X402406Y-48259D01*
X405245Y-38634D01*
G01X398258D02*
X402406Y-48259D01*
G01X418160Y-50300D02*
X416850Y-50008D01*
X415540Y-48842D01*
X414666Y-46800D01*
X414230Y-44467D01*
X414666Y-42133D01*
X415540Y-40092D01*
X416850Y-38925D01*
X418160Y-38634D01*
X419470Y-38925D01*
X420780Y-40092D01*
X421653Y-42133D01*
X421872Y-44467D01*
X421653Y-46800D01*
X420780Y-48842D01*
X419470Y-50008D01*
X418160Y-50300D01*
G01X431948Y-38634D02*
Y-46800D01*
X432822Y-48842D01*
X434132Y-50008D01*
X435660Y-50300D01*
X437188Y-50008D01*
X438498Y-48842D01*
X439372Y-46800D01*
G01Y-50300D02*
Y-38634D01*
G01X450103Y-50300D02*
Y-38634D01*
G01Y-40967D02*
X451195Y-39800D01*
X452287Y-38925D01*
X453815Y-38634D01*
X454906Y-38925D01*
X456217Y-39800D01*
G01X485103Y-50300D02*
Y-38634D01*
G01Y-40967D02*
X486195Y-39800D01*
X487287Y-38925D01*
X488815Y-38634D01*
X489906Y-38925D01*
X491217Y-39800D01*
G01X502385Y-42425D02*
X509372D01*
X508717Y-40383D01*
X507625Y-39217D01*
X506097Y-38634D01*
X504568Y-38925D01*
X503258Y-39800D01*
X502385Y-41842D01*
X501948Y-43592D01*
Y-45342D01*
X502385Y-47092D01*
X503477Y-48842D01*
X504787Y-50008D01*
X506315Y-50300D01*
X507843Y-49717D01*
X509372Y-47967D01*
G01X521850Y-50300D02*
Y-35425D01*
X522287Y-33967D01*
X523160Y-33092D01*
X524470Y-32800D01*
X525780Y-33383D01*
X526435Y-34842D01*
G01X523815Y-39800D02*
X519448D01*
G01X537385Y-42425D02*
X544372D01*
X543717Y-40383D01*
X542625Y-39217D01*
X541097Y-38634D01*
X539568Y-38925D01*
X538258Y-39800D01*
X537385Y-41842D01*
X536948Y-43592D01*
Y-45342D01*
X537385Y-47092D01*
X538477Y-48842D01*
X539787Y-50008D01*
X541315Y-50300D01*
X542843Y-49717D01*
X544372Y-47967D01*
G01X555103Y-50300D02*
Y-38634D01*
G01Y-40967D02*
X556195Y-39800D01*
X557287Y-38925D01*
X558815Y-38634D01*
X559906Y-38925D01*
X561217Y-39800D01*
G01X572385Y-42425D02*
X579372D01*
X578717Y-40383D01*
X577625Y-39217D01*
X576097Y-38634D01*
X574568Y-38925D01*
X573258Y-39800D01*
X572385Y-41842D01*
X571948Y-43592D01*
Y-45342D01*
X572385Y-47092D01*
X573477Y-48842D01*
X574787Y-50008D01*
X576315Y-50300D01*
X577843Y-49717D01*
X579372Y-47967D01*
G01X589448Y-50300D02*
Y-38634D01*
G01Y-41550D02*
X590322Y-40092D01*
X591632Y-38925D01*
X593378Y-38634D01*
X594906Y-38925D01*
X596217Y-40092D01*
X596872Y-42133D01*
Y-50300D01*
G01X614153Y-40092D02*
X612625Y-38925D01*
X611315Y-38634D01*
X609568Y-39217D01*
X608258Y-40383D01*
X607385Y-42425D01*
X607166Y-44467D01*
X607385Y-46509D01*
X608258Y-48259D01*
X609568Y-49717D01*
X611315Y-50300D01*
X612843Y-49717D01*
X614153Y-48550D01*
G01X624885Y-42425D02*
X631872D01*
X631217Y-40383D01*
X630125Y-39217D01*
X628597Y-38634D01*
X627068Y-38925D01*
X625758Y-39800D01*
X624885Y-41842D01*
X624448Y-43592D01*
Y-45342D01*
X624885Y-47092D01*
X625977Y-48842D01*
X627287Y-50008D01*
X628815Y-50300D01*
X630343Y-49717D01*
X631872Y-47967D01*
G01X663160Y-32800D02*
Y-50300D01*
G01X660103Y-38634D02*
X666217D01*
G01X680660Y-50300D02*
X679350Y-50008D01*
X678040Y-48842D01*
X677166Y-46800D01*
X676730Y-44467D01*
X677166Y-42133D01*
X678040Y-40092D01*
X679350Y-38925D01*
X680660Y-38634D01*
X681970Y-38925D01*
X683280Y-40092D01*
X684153Y-42133D01*
X684372Y-44467D01*
X684153Y-46800D01*
X683280Y-48842D01*
X681970Y-50008D01*
X680660Y-50300D01*
G01X714350D02*
Y-35425D01*
X714787Y-33967D01*
X715660Y-33092D01*
X716970Y-32800D01*
X718280Y-33383D01*
X718935Y-34842D01*
G01X716315Y-39800D02*
X711948D01*
G01X733160Y-38634D02*
Y-50300D01*
G01Y-33967D02*
X732723Y-33675D01*
Y-33092D01*
X733160Y-32800D01*
X733597Y-33092D01*
Y-33675D01*
X733160Y-33967D01*
G01X746948Y-50300D02*
Y-38634D01*
G01Y-41550D02*
X747822Y-40092D01*
X749132Y-38925D01*
X750878Y-38634D01*
X752406Y-38925D01*
X753717Y-40092D01*
X754372Y-42133D01*
Y-50300D01*
G01X772090Y-32800D02*
Y-50300D01*
G01Y-47676D02*
X771217Y-49134D01*
X769906Y-50008D01*
X768378Y-50300D01*
X766632Y-49717D01*
X765322Y-48259D01*
X764448Y-46509D01*
X764230Y-44467D01*
X764448Y-42425D01*
X765322Y-40675D01*
X766632Y-39217D01*
X768378Y-38634D01*
X769906Y-38925D01*
X770998Y-39509D01*
X772090Y-40675D01*
G01X803160Y-32800D02*
Y-50300D01*
G01X800103Y-38634D02*
X806217D01*
G01X816948Y-50300D02*
Y-32800D01*
G01Y-41258D02*
X818040Y-39800D01*
X819132Y-38925D01*
X820878Y-38634D01*
X822188Y-38925D01*
X823717Y-40092D01*
X824372Y-41842D01*
Y-50300D01*
G01X834885Y-42425D02*
X841872D01*
X841217Y-40383D01*
X840125Y-39217D01*
X838597Y-38634D01*
X837068Y-38925D01*
X835758Y-39800D01*
X834885Y-41842D01*
X834448Y-43592D01*
Y-45342D01*
X834885Y-47092D01*
X835977Y-48842D01*
X837287Y-50008D01*
X838815Y-50300D01*
X840343Y-49717D01*
X841872Y-47967D01*
G01X868357Y-50300D02*
Y-32800D01*
X872723D01*
X874470Y-33675D01*
X875780Y-34842D01*
X876872Y-36591D01*
X877745Y-38634D01*
X877963Y-41550D01*
X877745Y-44467D01*
X876872Y-46509D01*
X875780Y-48259D01*
X874470Y-49425D01*
X872723Y-50300D01*
X868357D01*
G01X886293D02*
Y-32800D01*
X891533D01*
X893280Y-33675D01*
X894590Y-35717D01*
X895027Y-38050D01*
X894590Y-40383D01*
X893498Y-42133D01*
X891533Y-43009D01*
X886293D01*
G01X925660Y-38634D02*
Y-50300D01*
G01Y-33967D02*
X925223Y-33675D01*
Y-33092D01*
X925660Y-32800D01*
X926097Y-33092D01*
Y-33675D01*
X925660Y-33967D01*
G01X936610Y-50300D02*
Y-38634D01*
G01Y-41842D02*
X937265Y-40383D01*
X938357Y-39217D01*
X939885Y-38634D01*
X941413Y-39217D01*
X942505Y-40383D01*
X943160Y-41842D01*
Y-50300D01*
G01Y-41842D02*
X943815Y-40383D01*
X944906Y-39217D01*
X946435Y-38634D01*
X947963Y-39217D01*
X949055Y-40383D01*
X949710Y-42133D01*
Y-50300D01*
G01X956730Y-56133D02*
Y-38634D01*
G01Y-41258D02*
X957822Y-39800D01*
X958913Y-38925D01*
X960660Y-38634D01*
X962188Y-38925D01*
X963717Y-40383D01*
X964372Y-42425D01*
X964590Y-44467D01*
X964372Y-46509D01*
X963717Y-48550D01*
X962406Y-49717D01*
X960660Y-50300D01*
X959132Y-50008D01*
X957603Y-49134D01*
X956730Y-47967D01*
G01X974885Y-42425D02*
X981872D01*
X981217Y-40383D01*
X980125Y-39217D01*
X978597Y-38634D01*
X977068Y-38925D01*
X975758Y-39800D01*
X974885Y-41842D01*
X974448Y-43592D01*
Y-45342D01*
X974885Y-47092D01*
X975977Y-48842D01*
X977287Y-50008D01*
X978815Y-50300D01*
X980343Y-49717D01*
X981872Y-47967D01*
G01X999590Y-32800D02*
Y-50300D01*
G01Y-47676D02*
X998717Y-49134D01*
X997406Y-50008D01*
X995878Y-50300D01*
X994132Y-49717D01*
X992822Y-48259D01*
X991948Y-46509D01*
X991730Y-44467D01*
X991948Y-42425D01*
X992822Y-40675D01*
X994132Y-39217D01*
X995878Y-38634D01*
X997406Y-38925D01*
X998498Y-39509D01*
X999590Y-40675D01*
G01X1017090Y-50300D02*
Y-38634D01*
G01Y-40675D02*
X1016217Y-39509D01*
X1014906Y-38925D01*
X1013378Y-38634D01*
X1011850Y-39217D01*
X1010540Y-40383D01*
X1009666Y-42133D01*
X1009230Y-44467D01*
X1009666Y-46800D01*
X1010540Y-48550D01*
X1011850Y-49717D01*
X1013378Y-50300D01*
X1014906Y-50008D01*
X1016217Y-49134D01*
X1017090Y-47967D01*
G01X1026948Y-50300D02*
Y-38634D01*
G01Y-41550D02*
X1027822Y-40092D01*
X1029132Y-38925D01*
X1030878Y-38634D01*
X1032406Y-38925D01*
X1033717Y-40092D01*
X1034372Y-42133D01*
Y-50300D01*
G01X1051653Y-40092D02*
X1050125Y-38925D01*
X1048815Y-38634D01*
X1047068Y-39217D01*
X1045758Y-40383D01*
X1044885Y-42425D01*
X1044666Y-44467D01*
X1044885Y-46509D01*
X1045758Y-48259D01*
X1047068Y-49717D01*
X1048815Y-50300D01*
X1050343Y-49717D01*
X1051653Y-48550D01*
G01X1062385Y-42425D02*
X1069372D01*
X1068717Y-40383D01*
X1067625Y-39217D01*
X1066097Y-38634D01*
X1064568Y-38925D01*
X1063258Y-39800D01*
X1062385Y-41842D01*
X1061948Y-43592D01*
Y-45342D01*
X1062385Y-47092D01*
X1063477Y-48842D01*
X1064787Y-50008D01*
X1066315Y-50300D01*
X1067843Y-49717D01*
X1069372Y-47967D01*
G01X1100660Y-32800D02*
Y-50300D01*
G01X1097603Y-38634D02*
X1103717D01*
G01X1115103Y-50300D02*
Y-38634D01*
G01Y-40967D02*
X1116195Y-39800D01*
X1117287Y-38925D01*
X1118815Y-38634D01*
X1119906Y-38925D01*
X1121217Y-39800D01*
G01X1139590Y-50300D02*
Y-38634D01*
G01Y-40675D02*
X1138717Y-39509D01*
X1137406Y-38925D01*
X1135878Y-38634D01*
X1134350Y-39217D01*
X1133040Y-40383D01*
X1132166Y-42133D01*
X1131730Y-44467D01*
X1132166Y-46800D01*
X1133040Y-48550D01*
X1134350Y-49717D01*
X1135878Y-50300D01*
X1137406Y-50008D01*
X1138717Y-49134D01*
X1139590Y-47967D01*
G01X1156653Y-40092D02*
X1155125Y-38925D01*
X1153815Y-38634D01*
X1152068Y-39217D01*
X1150758Y-40383D01*
X1149885Y-42425D01*
X1149666Y-44467D01*
X1149885Y-46509D01*
X1150758Y-48259D01*
X1152068Y-49717D01*
X1153815Y-50300D01*
X1155343Y-49717D01*
X1156653Y-48550D01*
G01X1167385Y-42425D02*
X1174372D01*
X1173717Y-40383D01*
X1172625Y-39217D01*
X1171097Y-38634D01*
X1169568Y-38925D01*
X1168258Y-39800D01*
X1167385Y-41842D01*
X1166948Y-43592D01*
Y-45342D01*
X1167385Y-47092D01*
X1168477Y-48842D01*
X1169787Y-50008D01*
X1171315Y-50300D01*
X1172843Y-49717D01*
X1174372Y-47967D01*
G01X1184885Y-48259D02*
X1185977Y-49425D01*
X1187505Y-50300D01*
X1188815D01*
X1190125Y-49717D01*
X1190998Y-48842D01*
X1191435Y-47676D01*
X1191217Y-45925D01*
X1190343Y-45050D01*
X1186413Y-43300D01*
X1185540Y-41258D01*
X1185977Y-39800D01*
X1186850Y-38925D01*
X1188160Y-38634D01*
X1189470Y-38925D01*
X1190780Y-39800D01*
G01X1223160Y-38634D02*
Y-50300D01*
G01Y-33967D02*
X1222723Y-33675D01*
Y-33092D01*
X1223160Y-32800D01*
X1223597Y-33092D01*
Y-33675D01*
X1223160Y-33967D01*
G01X1236948Y-50300D02*
Y-38634D01*
G01Y-41550D02*
X1237822Y-40092D01*
X1239132Y-38925D01*
X1240878Y-38634D01*
X1242406Y-38925D01*
X1243717Y-40092D01*
X1244372Y-42133D01*
Y-50300D01*
G01X1275660D02*
Y-32800D01*
G01X1297090Y-50300D02*
Y-38634D01*
G01Y-40675D02*
X1296217Y-39509D01*
X1294906Y-38925D01*
X1293378Y-38634D01*
X1291850Y-39217D01*
X1290540Y-40383D01*
X1289666Y-42133D01*
X1289230Y-44467D01*
X1289666Y-46800D01*
X1290540Y-48550D01*
X1291850Y-49717D01*
X1293378Y-50300D01*
X1294906Y-50008D01*
X1296217Y-49134D01*
X1297090Y-47967D01*
G01X1306075Y-55550D02*
X1307385Y-56133D01*
X1309132Y-55550D01*
X1310223Y-54384D01*
X1311097Y-52925D01*
X1312406Y-48259D01*
X1315245Y-38634D01*
G01X1308258D02*
X1312406Y-48259D01*
G01X1324885Y-42425D02*
X1331872D01*
X1331217Y-40383D01*
X1330125Y-39217D01*
X1328597Y-38634D01*
X1327068Y-38925D01*
X1325758Y-39800D01*
X1324885Y-41842D01*
X1324448Y-43592D01*
Y-45342D01*
X1324885Y-47092D01*
X1325977Y-48842D01*
X1327287Y-50008D01*
X1328815Y-50300D01*
X1330343Y-49717D01*
X1331872Y-47967D01*
G01X1342603Y-50300D02*
Y-38634D01*
G01Y-40967D02*
X1343695Y-39800D01*
X1344787Y-38925D01*
X1346315Y-38634D01*
X1347406Y-38925D01*
X1348717Y-39800D01*
G01X1376293Y-32800D02*
Y-50300D01*
X1385027D01*
G01X1394012Y-43009D02*
X1395540Y-40967D01*
X1396850Y-39800D01*
X1398597Y-39217D01*
X1400125Y-39800D01*
X1401217Y-40967D01*
X1402090Y-42717D01*
X1402308Y-44758D01*
X1402090Y-46509D01*
X1401217Y-48259D01*
X1399906Y-49717D01*
X1398378Y-50300D01*
X1396632Y-49717D01*
X1395103Y-47967D01*
X1394230Y-45342D01*
X1394012Y-42425D01*
X1394448Y-38634D01*
X1395103Y-36591D01*
X1396195Y-34550D01*
X1397723Y-33092D01*
X1399252Y-32800D01*
X1400780Y-33383D01*
X1401872Y-34842D01*
G01X1415660Y-50883D02*
X1415223Y-50592D01*
Y-50008D01*
X1415660Y-49717D01*
X1416097Y-50008D01*
Y-50592D01*
X1415660Y-50883D01*
G01X617008Y706896D02*
Y724396D01*
X621374D01*
X623121Y723521D01*
X624431Y722354D01*
X625523Y720605D01*
X626396Y718562D01*
X626614Y715646D01*
X626396Y712729D01*
X625523Y710687D01*
X624431Y708937D01*
X623121Y707771D01*
X621374Y706896D01*
X617008D01*
G01X634944D02*
Y724396D01*
X640184D01*
X641931Y723521D01*
X643241Y721479D01*
X643678Y719146D01*
X643241Y716813D01*
X642149Y715063D01*
X640184Y714187D01*
X634944D01*
G01X671691Y724396D02*
X676931D01*
G01X674311D02*
Y706896D01*
G01X671691D02*
X676931D01*
G01X686134D02*
Y724396D01*
X691811Y709813D01*
X697488Y724396D01*
Y706896D01*
G01X704944D02*
Y724396D01*
X710184D01*
X711931Y723521D01*
X713241Y721479D01*
X713678Y719146D01*
X713241Y716813D01*
X712149Y715063D01*
X710184Y714187D01*
X704944D01*
G01X731178Y706896D02*
X722444D01*
Y724396D01*
X731178D01*
G01X727684Y715938D02*
X722444D01*
G01X739508Y706896D02*
Y724396D01*
X743874D01*
X745621Y723521D01*
X746931Y722354D01*
X748023Y720605D01*
X748896Y718562D01*
X749114Y715646D01*
X748896Y712729D01*
X748023Y710687D01*
X746931Y708937D01*
X745621Y707771D01*
X743874Y706896D01*
X739508D01*
G01X756352D02*
X761811Y724396D01*
X767270Y706896D01*
G01X765304Y713021D02*
X758317D01*
G01X774289Y706896D02*
Y724396D01*
X784333Y706896D01*
Y724396D01*
G01X801614Y722937D02*
X800304Y723813D01*
X798776Y724396D01*
X797029D01*
X795064Y723521D01*
X793536Y722063D01*
X792444Y720312D01*
X791571Y717396D01*
X791352Y714771D01*
X791789Y712146D01*
X792444Y710396D01*
X793754Y708646D01*
X795283Y707479D01*
X796811Y706896D01*
X798339D01*
X799868Y707479D01*
X801178Y708354D01*
X802270Y709520D01*
G01X818678Y706896D02*
X809944D01*
Y724396D01*
X818678D01*
G01X815184Y715938D02*
X809944D01*
G01X849311Y724396D02*
Y706896D01*
G01X844289Y724396D02*
X854333D01*
G01X861352Y706896D02*
X866811Y724396D01*
X872270Y706896D01*
G01X870304Y713021D02*
X863317D01*
G01X886057Y716229D02*
X886931Y717104D01*
X887586Y718562D01*
X888023Y720605D01*
X887586Y722354D01*
X886713Y723521D01*
X885184Y724396D01*
X879289D01*
Y706896D01*
X886494D01*
X888023Y708062D01*
X888896Y709813D01*
X889333Y711854D01*
X888896Y713896D01*
X887586Y715646D01*
X886057Y716229D01*
X879289D01*
G01X897444Y724396D02*
Y706896D01*
X906178D01*
G01X923678D02*
X914944D01*
Y724396D01*
X923678D01*
G01X920184Y715938D02*
X914944D01*
G01X936811Y706313D02*
X936374Y706604D01*
Y707188D01*
X936811Y707479D01*
X937248Y707188D01*
Y706604D01*
X936811Y706313D01*
G01Y714187D02*
X936374Y714479D01*
Y715063D01*
X936811Y715354D01*
X937248Y715063D01*
Y714479D01*
X936811Y714187D01*
G01X967444Y724396D02*
Y706896D01*
X976178D01*
G01X985163Y714187D02*
X986691Y716229D01*
X988001Y717396D01*
X989748Y717979D01*
X991276Y717396D01*
X992368Y716229D01*
X993241Y714479D01*
X993459Y712438D01*
X993241Y710687D01*
X992368Y708937D01*
X991057Y707479D01*
X989529Y706896D01*
X987783Y707479D01*
X986254Y709229D01*
X985381Y711854D01*
X985163Y714771D01*
X985599Y718562D01*
X986254Y720605D01*
X987346Y722646D01*
X988874Y724104D01*
X990403Y724396D01*
X991931Y723813D01*
X993023Y722354D01*
G01X638891Y689746D02*
X644131D01*
G01X641511D02*
Y672246D01*
G01X638891D02*
X644131D01*
G01X653334D02*
Y689746D01*
X659011Y675163D01*
X664688Y689746D01*
Y672246D01*
G01X672144D02*
Y689746D01*
X677384D01*
X679131Y688871D01*
X680441Y686829D01*
X680878Y684496D01*
X680441Y682163D01*
X679349Y680413D01*
X677384Y679537D01*
X672144D01*
G01X692919Y666413D02*
X690736Y669329D01*
X689644Y672246D01*
Y683912D01*
X690736Y686829D01*
X692919Y689746D01*
G01X711511Y672246D02*
X709764Y672538D01*
X708236Y673704D01*
X706926Y675454D01*
X706052Y677496D01*
X705616Y679829D01*
Y682163D01*
X706052Y684496D01*
X706926Y686538D01*
X708236Y688287D01*
X709764Y689454D01*
X711511Y689746D01*
X713257Y689454D01*
X714786Y688287D01*
X716096Y686538D01*
X716970Y684496D01*
X717406Y682163D01*
Y679829D01*
X716970Y677496D01*
X716096Y675454D01*
X714786Y673704D01*
X713257Y672538D01*
X711511Y672246D01*
G01X725299D02*
Y689746D01*
G01Y681288D02*
X726391Y682746D01*
X727483Y683621D01*
X729229Y683912D01*
X730539Y683621D01*
X732068Y682454D01*
X732723Y680704D01*
Y672246D01*
G01X739961D02*
Y683912D01*
G01Y680704D02*
X740616Y682163D01*
X741708Y683329D01*
X743236Y683912D01*
X744764Y683329D01*
X745856Y682163D01*
X746511Y680704D01*
Y672246D01*
G01Y680704D02*
X747166Y682163D01*
X748257Y683329D01*
X749786Y683912D01*
X751314Y683329D01*
X752406Y682163D01*
X753061Y680413D01*
Y672246D01*
G01X765103Y666413D02*
X767286Y669329D01*
X768378Y672246D01*
Y683912D01*
X767286Y686829D01*
X765103Y689746D01*
G01X676511Y637596D02*
X678039Y637888D01*
X679786Y638762D01*
X680878Y640220D01*
X681314Y642263D01*
X680878Y644304D01*
X679568Y646054D01*
X677603Y646929D01*
X675419D01*
X674109Y647513D01*
X673017Y648971D01*
X672581Y651012D01*
X673236Y653054D01*
X674764Y654513D01*
X676511Y655096D01*
X678257Y654513D01*
X679786Y653054D01*
X680441Y651012D01*
X680004Y648971D01*
X678913Y647513D01*
X677603Y646929D01*
X675419D01*
X673454Y646054D01*
X672144Y644304D01*
X671708Y642263D01*
X672144Y640220D01*
X673236Y638762D01*
X674983Y637888D01*
X676511Y637596D01*
G01X689208Y640220D02*
X690517Y638762D01*
X692046Y637888D01*
X694011Y637596D01*
X695976Y638179D01*
X697504Y639346D01*
X698596Y641387D01*
X698814Y643721D01*
X698378Y646054D01*
X697286Y647513D01*
X695757Y648679D01*
X694229Y648971D01*
X692701Y648679D01*
X690736Y647513D01*
X691391Y655096D01*
X697286D01*
G01X711511Y637013D02*
X711074Y637304D01*
Y637888D01*
X711511Y638179D01*
X711948Y637888D01*
Y637304D01*
X711511Y637013D01*
G01X729011Y655096D02*
X727264Y654513D01*
X725954Y653054D01*
X725081Y651305D01*
X724426Y648971D01*
X724208Y646346D01*
X724426Y643721D01*
X725081Y641387D01*
X725954Y639637D01*
X727264Y638179D01*
X729011Y637596D01*
X730757Y638179D01*
X732068Y639637D01*
X732941Y641387D01*
X733596Y643721D01*
X733814Y646346D01*
X733596Y648971D01*
X732941Y651305D01*
X732068Y653054D01*
X730757Y654513D01*
X729011Y655096D01*
G01X818711Y689746D02*
X821767Y672246D01*
X825261Y689746D01*
X828754Y672246D01*
X831811Y689746D01*
G01X840141D02*
X845381D01*
G01X842761D02*
Y672246D01*
G01X840141D02*
X845381D01*
G01X855458D02*
Y689746D01*
X859824D01*
X861571Y688871D01*
X862881Y687704D01*
X863973Y685955D01*
X864846Y683912D01*
X865064Y680996D01*
X864846Y678079D01*
X863973Y676037D01*
X862881Y674287D01*
X861571Y673121D01*
X859824Y672246D01*
X855458D01*
G01X877761Y689746D02*
Y672246D01*
G01X872739Y689746D02*
X882783D01*
G01X890676Y672246D02*
Y689746D01*
G01X899846D02*
Y672246D01*
G01Y680996D02*
X890676D01*
G01X911669Y666413D02*
X909486Y669329D01*
X908394Y672246D01*
Y683912D01*
X909486Y686829D01*
X911669Y689746D01*
G01X923711Y672246D02*
Y683912D01*
G01Y680704D02*
X924366Y682163D01*
X925458Y683329D01*
X926986Y683912D01*
X928514Y683329D01*
X929606Y682163D01*
X930261Y680704D01*
Y672246D01*
G01Y680704D02*
X930916Y682163D01*
X932007Y683329D01*
X933536Y683912D01*
X935064Y683329D01*
X936156Y682163D01*
X936811Y680413D01*
Y672246D01*
G01X947761Y683912D02*
Y672246D01*
G01Y688579D02*
X947324Y688871D01*
Y689454D01*
X947761Y689746D01*
X948198Y689454D01*
Y688871D01*
X947761Y688579D01*
G01X965261Y672246D02*
Y689746D01*
G01X979486Y674287D02*
X980578Y673121D01*
X982106Y672246D01*
X983416D01*
X984726Y672829D01*
X985599Y673704D01*
X986036Y674870D01*
X985818Y676621D01*
X984944Y677496D01*
X981014Y679246D01*
X980141Y681288D01*
X980578Y682746D01*
X981451Y683621D01*
X982761Y683912D01*
X984071Y683621D01*
X985381Y682746D01*
G01X1001353Y666413D02*
X1003536Y669329D01*
X1004628Y672246D01*
Y683912D01*
X1003536Y686829D01*
X1001353Y689746D01*
G01X860261Y637596D02*
X861789Y637888D01*
X863536Y638762D01*
X864628Y640220D01*
X865064Y642263D01*
X864628Y644304D01*
X863318Y646054D01*
X861353Y646929D01*
X859169D01*
X857859Y647513D01*
X856767Y648971D01*
X856331Y651012D01*
X856986Y653054D01*
X858514Y654513D01*
X860261Y655096D01*
X862007Y654513D01*
X863536Y653054D01*
X864191Y651012D01*
X863754Y648971D01*
X862663Y647513D01*
X861353Y646929D01*
X859169D01*
X857204Y646054D01*
X855894Y644304D01*
X855458Y642263D01*
X855894Y640220D01*
X856986Y638762D01*
X858733Y637888D01*
X860261Y637596D01*
G01X877761Y637013D02*
X877324Y637304D01*
Y637888D01*
X877761Y638179D01*
X878198Y637888D01*
Y637304D01*
X877761Y637013D01*
G01X897881Y637596D02*
Y655096D01*
X889802Y642554D01*
X900720D01*
G01X908831Y637013D02*
X916691Y655096D01*
G01X926549Y639637D02*
X928078Y638179D01*
X929824Y637596D01*
X931571Y638179D01*
X933099Y639929D01*
X934191Y642554D01*
X934628Y645179D01*
Y648387D01*
X934191Y651012D01*
X933099Y653346D01*
X931789Y654513D01*
X930261Y655096D01*
X928514Y654513D01*
X927204Y653346D01*
X926331Y651596D01*
X925894Y649262D01*
X926331Y647221D01*
X927423Y645179D01*
X928733Y644012D01*
X930261Y643721D01*
X932007Y644304D01*
X933318Y645763D01*
X934628Y648387D01*
G01X947761Y637013D02*
X947324Y637304D01*
Y637888D01*
X947761Y638179D01*
X948198Y637888D01*
Y637304D01*
X947761Y637013D01*
G01X965261Y655096D02*
X963514Y654513D01*
X962204Y653054D01*
X961331Y651305D01*
X960676Y648971D01*
X960458Y646346D01*
X960676Y643721D01*
X961331Y641387D01*
X962204Y639637D01*
X963514Y638179D01*
X965261Y637596D01*
X967007Y638179D01*
X968318Y639637D01*
X969191Y641387D01*
X969846Y643721D01*
X970064Y646346D01*
X969846Y648971D01*
X969191Y651305D01*
X968318Y653054D01*
X967007Y654513D01*
X965261Y655096D01*
G01X1061511Y689746D02*
Y672246D01*
G01X1056489Y689746D02*
X1066533D01*
G01X1079011Y672246D02*
Y680121D01*
X1074644Y689746D01*
G01X1083378D02*
X1079011Y680121D01*
G01X1092144Y672246D02*
Y689746D01*
X1097384D01*
X1099131Y688871D01*
X1100441Y686829D01*
X1100878Y684496D01*
X1100441Y682163D01*
X1099349Y680413D01*
X1097384Y679537D01*
X1092144D01*
G01X1118378Y672246D02*
X1109644D01*
Y689746D01*
X1118378D01*
G01X1114884Y681288D02*
X1109644D01*
G01X1074208Y637596D02*
Y655096D01*
X1078574D01*
X1080321Y654221D01*
X1081631Y653054D01*
X1082723Y651305D01*
X1083596Y649262D01*
X1083814Y646346D01*
X1083596Y643429D01*
X1082723Y641387D01*
X1081631Y639637D01*
X1080321Y638471D01*
X1078574Y637596D01*
X1074208D01*
G01X1092144D02*
Y655096D01*
X1097384D01*
X1099131Y654221D01*
X1100441Y652179D01*
X1100878Y649846D01*
X1100441Y647513D01*
X1099349Y645763D01*
X1097384Y644887D01*
X1092144D01*
G01X1162144Y672246D02*
Y689746D01*
X1167603D01*
X1169349Y688871D01*
X1170441Y687704D01*
X1170878Y685371D01*
X1170441Y683037D01*
X1169131Y681579D01*
X1167603Y680704D01*
X1162144D01*
G01X1167603D02*
X1170878Y672246D01*
G01X1180736Y680121D02*
X1187723D01*
X1187068Y682163D01*
X1185976Y683329D01*
X1184448Y683912D01*
X1182919Y683621D01*
X1181609Y682746D01*
X1180736Y680704D01*
X1180299Y678954D01*
Y677204D01*
X1180736Y675454D01*
X1181828Y673704D01*
X1183138Y672538D01*
X1184666Y672246D01*
X1186194Y672829D01*
X1187723Y674579D01*
G01X1200201Y672246D02*
Y687121D01*
X1200638Y688579D01*
X1201511Y689454D01*
X1202821Y689746D01*
X1204131Y689163D01*
X1204786Y687704D01*
G01X1202166Y682746D02*
X1197799D01*
G01X1219011Y671663D02*
X1218574Y671954D01*
Y672538D01*
X1219011Y672829D01*
X1219448Y672538D01*
Y671954D01*
X1219011Y671663D01*
G01X1249644Y672246D02*
Y689746D01*
X1254884D01*
X1256631Y688871D01*
X1257941Y686829D01*
X1258378Y684496D01*
X1257941Y682163D01*
X1256849Y680413D01*
X1254884Y679537D01*
X1249644D01*
G01X1271511Y672246D02*
Y689746D01*
G01X1292941Y672246D02*
Y683912D01*
G01Y681871D02*
X1292068Y683037D01*
X1290757Y683621D01*
X1289229Y683912D01*
X1287701Y683329D01*
X1286391Y682163D01*
X1285517Y680413D01*
X1285081Y678079D01*
X1285517Y675746D01*
X1286391Y673996D01*
X1287701Y672829D01*
X1289229Y672246D01*
X1290757Y672538D01*
X1292068Y673412D01*
X1292941Y674579D01*
G01X1302799Y672246D02*
Y683912D01*
G01Y680996D02*
X1303673Y682454D01*
X1304983Y683621D01*
X1306729Y683912D01*
X1308257Y683621D01*
X1309568Y682454D01*
X1310223Y680413D01*
Y672246D01*
G01X1320736Y680121D02*
X1327723D01*
X1327068Y682163D01*
X1325976Y683329D01*
X1324448Y683912D01*
X1322919Y683621D01*
X1321609Y682746D01*
X1320736Y680704D01*
X1320299Y678954D01*
Y677204D01*
X1320736Y675454D01*
X1321828Y673704D01*
X1323138Y672538D01*
X1324666Y672246D01*
X1326194Y672829D01*
X1327723Y674579D01*
G01X1232144Y655096D02*
Y637596D01*
X1240878D01*
G01X1249208Y640220D02*
X1250517Y638762D01*
X1252046Y637888D01*
X1254011Y637596D01*
X1255976Y638179D01*
X1257504Y639346D01*
X1258596Y641387D01*
X1258814Y643721D01*
X1258378Y646054D01*
X1257286Y647513D01*
X1255757Y648679D01*
X1254229Y648971D01*
X1252701Y648679D01*
X1250736Y647513D01*
X1251391Y655096D01*
X1257286D01*
G01X1441811Y649262D02*
Y637596D01*
G01Y653929D02*
X1441374Y654221D01*
Y654804D01*
X1441811Y655096D01*
X1442248Y654804D01*
Y654221D01*
X1441811Y653929D01*
G01X1456036Y639637D02*
X1457128Y638471D01*
X1458656Y637596D01*
X1459966D01*
X1461276Y638179D01*
X1462149Y639054D01*
X1462586Y640220D01*
X1462368Y641971D01*
X1461494Y642846D01*
X1457564Y644596D01*
X1456691Y646638D01*
X1457128Y648096D01*
X1458001Y648971D01*
X1459311Y649262D01*
X1460621Y648971D01*
X1461931Y648096D01*
G01X1489289Y637596D02*
Y655096D01*
X1499333Y637596D01*
Y655096D01*
G01X1511811Y637596D02*
X1510064Y637888D01*
X1508536Y639054D01*
X1507226Y640804D01*
X1506352Y642846D01*
X1505916Y645179D01*
Y647513D01*
X1506352Y649846D01*
X1507226Y651888D01*
X1508536Y653637D01*
X1510064Y654804D01*
X1511811Y655096D01*
X1513557Y654804D01*
X1515086Y653637D01*
X1516396Y651888D01*
X1517270Y649846D01*
X1517706Y647513D01*
Y645179D01*
X1517270Y642846D01*
X1516396Y640804D01*
X1515086Y639054D01*
X1513557Y637888D01*
X1511811Y637596D01*
G01X1529311Y655096D02*
Y637596D01*
G01X1524289Y655096D02*
X1534333D01*
G01X1560599Y649262D02*
Y641096D01*
X1561473Y639054D01*
X1562783Y637888D01*
X1564311Y637596D01*
X1565839Y637888D01*
X1567149Y639054D01*
X1568023Y641096D01*
G01Y637596D02*
Y649262D01*
G01X1578536Y639637D02*
X1579628Y638471D01*
X1581156Y637596D01*
X1582466D01*
X1583776Y638179D01*
X1584649Y639054D01*
X1585086Y640220D01*
X1584868Y641971D01*
X1583994Y642846D01*
X1580064Y644596D01*
X1579191Y646638D01*
X1579628Y648096D01*
X1580501Y648971D01*
X1581811Y649262D01*
X1583121Y648971D01*
X1584431Y648096D01*
G01X1596036Y645471D02*
X1603023D01*
X1602368Y647513D01*
X1601276Y648679D01*
X1599748Y649262D01*
X1598219Y648971D01*
X1596909Y648096D01*
X1596036Y646054D01*
X1595599Y644304D01*
Y642554D01*
X1596036Y640804D01*
X1597128Y639054D01*
X1598438Y637888D01*
X1599966Y637596D01*
X1601494Y638179D01*
X1603023Y639929D01*
G01X1620741Y655096D02*
Y637596D01*
G01Y640220D02*
X1619868Y638762D01*
X1618557Y637888D01*
X1617029Y637596D01*
X1615283Y638179D01*
X1613973Y639637D01*
X1613099Y641387D01*
X1612881Y643429D01*
X1613099Y645471D01*
X1613973Y647221D01*
X1615283Y648679D01*
X1617029Y649262D01*
X1618557Y648971D01*
X1619649Y648387D01*
X1620741Y647221D01*
G01X1367008Y671663D02*
X1376614Y684496D01*
G01X1371811Y686829D02*
Y669329D01*
G01X1376614Y671663D02*
X1367008Y684496D01*
G01X1365261Y678079D02*
X1378361D01*
G01X1403973D02*
X1409649D01*
G01X1437008Y672246D02*
Y689746D01*
X1441374D01*
X1443121Y688871D01*
X1444431Y687704D01*
X1445523Y685955D01*
X1446396Y683912D01*
X1446614Y680996D01*
X1446396Y678079D01*
X1445523Y676037D01*
X1444431Y674287D01*
X1443121Y673121D01*
X1441374Y672246D01*
X1437008D01*
G01X1456036Y680121D02*
X1463023D01*
X1462368Y682163D01*
X1461276Y683329D01*
X1459748Y683912D01*
X1458219Y683621D01*
X1456909Y682746D01*
X1456036Y680704D01*
X1455599Y678954D01*
Y677204D01*
X1456036Y675454D01*
X1457128Y673704D01*
X1458438Y672538D01*
X1459966Y672246D01*
X1461494Y672829D01*
X1463023Y674579D01*
G01X1473099Y672246D02*
Y683912D01*
G01Y680996D02*
X1473973Y682454D01*
X1475283Y683621D01*
X1477029Y683912D01*
X1478557Y683621D01*
X1479868Y682454D01*
X1480523Y680413D01*
Y672246D01*
G01X1494311D02*
X1493001Y672538D01*
X1491691Y673704D01*
X1490817Y675746D01*
X1490381Y678079D01*
X1490817Y680413D01*
X1491691Y682454D01*
X1493001Y683621D01*
X1494311Y683912D01*
X1495621Y683621D01*
X1496931Y682454D01*
X1497804Y680413D01*
X1498023Y678079D01*
X1497804Y675746D01*
X1496931Y673704D01*
X1495621Y672538D01*
X1494311Y672246D01*
G01X1511811Y689746D02*
Y672246D01*
G01X1508754Y683912D02*
X1514868D01*
G01X1526036Y680121D02*
X1533023D01*
X1532368Y682163D01*
X1531276Y683329D01*
X1529748Y683912D01*
X1528219Y683621D01*
X1526909Y682746D01*
X1526036Y680704D01*
X1525599Y678954D01*
Y677204D01*
X1526036Y675454D01*
X1527128Y673704D01*
X1528438Y672538D01*
X1529966Y672246D01*
X1531494Y672829D01*
X1533023Y674579D01*
G01X1543536Y674287D02*
X1544628Y673121D01*
X1546156Y672246D01*
X1547466D01*
X1548776Y672829D01*
X1549649Y673704D01*
X1550086Y674870D01*
X1549868Y676621D01*
X1548994Y677496D01*
X1545064Y679246D01*
X1544191Y681288D01*
X1544628Y682746D01*
X1545501Y683621D01*
X1546811Y683912D01*
X1548121Y683621D01*
X1549431Y682746D01*
G01X1581811Y689746D02*
Y672246D01*
G01X1578754Y683912D02*
X1584868D01*
G01X1595599Y672246D02*
Y689746D01*
G01Y681288D02*
X1596691Y682746D01*
X1597783Y683621D01*
X1599529Y683912D01*
X1600839Y683621D01*
X1602368Y682454D01*
X1603023Y680704D01*
Y672246D01*
G01X1620741D02*
Y683912D01*
G01Y681871D02*
X1619868Y683037D01*
X1618557Y683621D01*
X1617029Y683912D01*
X1615501Y683329D01*
X1614191Y682163D01*
X1613317Y680413D01*
X1612881Y678079D01*
X1613317Y675746D01*
X1614191Y673996D01*
X1615501Y672829D01*
X1617029Y672246D01*
X1618557Y672538D01*
X1619868Y673412D01*
X1620741Y674579D01*
G01X1634311Y689746D02*
Y672246D01*
G01X1631254Y683912D02*
X1637368D01*
G01X1669311Y689746D02*
Y672246D01*
G01X1666254Y683912D02*
X1672368D01*
G01X1683099Y672246D02*
Y689746D01*
G01Y681288D02*
X1684191Y682746D01*
X1685283Y683621D01*
X1687029Y683912D01*
X1688339Y683621D01*
X1689868Y682454D01*
X1690523Y680704D01*
Y672246D01*
G01X1704311Y683912D02*
Y672246D01*
G01Y688579D02*
X1703874Y688871D01*
Y689454D01*
X1704311Y689746D01*
X1704748Y689454D01*
Y688871D01*
X1704311Y688579D01*
G01X1718536Y674287D02*
X1719628Y673121D01*
X1721156Y672246D01*
X1722466D01*
X1723776Y672829D01*
X1724649Y673704D01*
X1725086Y674870D01*
X1724868Y676621D01*
X1723994Y677496D01*
X1720064Y679246D01*
X1719191Y681288D01*
X1719628Y682746D01*
X1720501Y683621D01*
X1721811Y683912D01*
X1723121Y683621D01*
X1724431Y682746D01*
G01X1754191Y689746D02*
X1759431D01*
G01X1756811D02*
Y672246D01*
G01X1754191D02*
X1759431D01*
G01X1767761D02*
Y683912D01*
G01Y680704D02*
X1768416Y682163D01*
X1769508Y683329D01*
X1771036Y683912D01*
X1772564Y683329D01*
X1773656Y682163D01*
X1774311Y680704D01*
Y672246D01*
G01Y680704D02*
X1774966Y682163D01*
X1776057Y683329D01*
X1777586Y683912D01*
X1779114Y683329D01*
X1780206Y682163D01*
X1780861Y680413D01*
Y672246D01*
G01X1787881Y666413D02*
Y683912D01*
G01Y681288D02*
X1788973Y682746D01*
X1790064Y683621D01*
X1791811Y683912D01*
X1793339Y683621D01*
X1794868Y682163D01*
X1795523Y680121D01*
X1795741Y678079D01*
X1795523Y676037D01*
X1794868Y673996D01*
X1793557Y672829D01*
X1791811Y672246D01*
X1790283Y672538D01*
X1788754Y673412D01*
X1787881Y674579D01*
G01X1806036Y680121D02*
X1813023D01*
X1812368Y682163D01*
X1811276Y683329D01*
X1809748Y683912D01*
X1808219Y683621D01*
X1806909Y682746D01*
X1806036Y680704D01*
X1805599Y678954D01*
Y677204D01*
X1806036Y675454D01*
X1807128Y673704D01*
X1808438Y672538D01*
X1809966Y672246D01*
X1811494Y672829D01*
X1813023Y674579D01*
G01X1830741Y689746D02*
Y672246D01*
G01Y674870D02*
X1829868Y673412D01*
X1828557Y672538D01*
X1827029Y672246D01*
X1825283Y672829D01*
X1823973Y674287D01*
X1823099Y676037D01*
X1822881Y678079D01*
X1823099Y680121D01*
X1823973Y681871D01*
X1825283Y683329D01*
X1827029Y683912D01*
X1828557Y683621D01*
X1829649Y683037D01*
X1830741Y681871D01*
G01X1848241Y672246D02*
Y683912D01*
G01Y681871D02*
X1847368Y683037D01*
X1846057Y683621D01*
X1844529Y683912D01*
X1843001Y683329D01*
X1841691Y682163D01*
X1840817Y680413D01*
X1840381Y678079D01*
X1840817Y675746D01*
X1841691Y673996D01*
X1843001Y672829D01*
X1844529Y672246D01*
X1846057Y672538D01*
X1847368Y673412D01*
X1848241Y674579D01*
G01X1858099Y672246D02*
Y683912D01*
G01Y680996D02*
X1858973Y682454D01*
X1860283Y683621D01*
X1862029Y683912D01*
X1863557Y683621D01*
X1864868Y682454D01*
X1865523Y680413D01*
Y672246D01*
G01X1882804Y682454D02*
X1881276Y683621D01*
X1879966Y683912D01*
X1878219Y683329D01*
X1876909Y682163D01*
X1876036Y680121D01*
X1875817Y678079D01*
X1876036Y676037D01*
X1876909Y674287D01*
X1878219Y672829D01*
X1879966Y672246D01*
X1881494Y672829D01*
X1882804Y673996D01*
G01X1893536Y680121D02*
X1900523D01*
X1899868Y682163D01*
X1898776Y683329D01*
X1897248Y683912D01*
X1895719Y683621D01*
X1894409Y682746D01*
X1893536Y680704D01*
X1893099Y678954D01*
Y677204D01*
X1893536Y675454D01*
X1894628Y673704D01*
X1895938Y672538D01*
X1897466Y672246D01*
X1898994Y672829D01*
X1900523Y674579D01*
G01X-25590Y9843D02*
G03X-15748Y0I9842J-1D01*
G01X-25590Y89370D02*
Y9843D01*
G01X-23622Y91339D02*
G03X-25590Y89370I1J-1969D01*
G01X-7874Y91339D02*
X-23622D01*
G01X-25590Y109055D02*
G03X-21653Y105118I3937J0D01*
G01X-25590Y357874D02*
Y109055D01*
G01X-21653Y105118D02*
X261811D01*
G01X-25590Y371654D02*
G03X-23622Y369685I1968J-1D01*
G01X-21653Y361811D02*
G03X-25590Y357874I0J-3937D01*
G01X1969Y361811D02*
X-21653D01*
G01X-7874Y369685D02*
X-23622D01*
G01X-25590Y459055D02*
Y371654D01*
G01X-23622Y461024D02*
G03X-25590Y459055I1J-1969D01*
G01X-7874Y461024D02*
X-23622D01*
G01X-25590Y478740D02*
G03X-21653Y474803I3937J0D01*
G01X-25590Y727559D02*
Y478740D01*
G01X-21653Y474803D02*
X261811D01*
G01X-21653Y731496D02*
G03X-25590Y727559I0J-3937D01*
G01X1969Y731496D02*
X-21653D01*
G01X-11811Y0D02*
G03X-7874Y3937I0J3937D01*
G01X-11811Y0D02*
X-15748D01*
G01X0Y3937D02*
G03X3937Y0I3937J0D01*
G01X-7874Y33071D02*
Y3937D01*
G01X0Y87402D02*
Y3937D01*
G01Y33071D02*
G03X-7874I-3937J0D01*
G01Y58268D02*
G03X0I3937J0D01*
G01X-7874Y91339D02*
Y58268D01*
G01X3937Y91339D02*
G03X0Y87402I0J-3937D01*
G01X5906Y357874D02*
G03X1969Y361811I-3937J0D01*
G01X0Y373622D02*
G03X3937Y369685I3937J0D01*
G01X-7874Y402756D02*
Y369685D01*
G01X0Y457087D02*
Y373622D01*
G01Y402756D02*
G03X-7874I-3937J0D01*
G01Y427953D02*
G03X0I3937J0D01*
G01X-7874Y461024D02*
Y427953D01*
G01X3937Y461024D02*
G03X0Y457087I0J-3937D01*
G01X5906Y727559D02*
G03X1969Y731496I-3937J0D01*
G01X3937Y0D02*
X372048D01*
G01X192914Y91339D02*
X3937D01*
G01X5906Y290748D02*
G03X9843Y286811I3937J0D01*
G01X5906Y357874D02*
Y290748D01*
G01X69488Y286811D02*
X9843D01*
G01X13780Y315650D02*
Y294685D01*
G01X69488D02*
X13780D01*
G01Y315650D02*
G03X5906I-3937J0D01*
G01Y340847D02*
G03X13780I3937J0D01*
G01Y361811D02*
Y340847D01*
G01X3937Y369685D02*
X372048D01*
G01X43307Y361811D02*
X13780D01*
G01X192914Y461024D02*
X3937D01*
G01X5906Y660433D02*
G03X9843Y656496I3937J0D01*
G01X5906Y727559D02*
Y660433D01*
G01X69488Y656496D02*
X9843D01*
G01X13780Y685335D02*
Y664370D01*
G01X69488D02*
X13780D01*
G01Y685335D02*
G03X5906I-3937J0D01*
G01Y710532D02*
G03X13780I3937J0D01*
G01Y729528D02*
Y710532D01*
G01X15748Y731496D02*
G03X13780Y729528I0J-1968D01*
G01X44819Y731496D02*
X15748D01*
G01X43307Y361811D02*
G03Y369685I0J3937D01*
G01X46675Y730184D02*
G03X44819Y731496I-1856J-657D01*
G01X46675Y730184D02*
G03X54098I3712J1313D01*
G01X53150Y181697D02*
G03X55118Y179729I1968J0D01*
G01X53150Y195477D02*
Y181697D01*
G01X55118Y179729D02*
X161418D01*
G01X55118Y197445D02*
G03X53150Y195477I0J-1968D01*
G01X161418Y197445D02*
X55118D01*
G01X73426Y282874D02*
G03X69488Y286811I-3937J0D01*
G01X81300Y282874D02*
G03X69488Y294685I-11811J0D01*
G01X74016Y369685D02*
G03Y361811I0J-3937D01*
G01X53150Y551382D02*
G03X55118Y549414I1968J0D01*
G01X53150Y565162D02*
Y551382D01*
G01X55118Y549414D02*
X161418D01*
G01X55118Y567130D02*
G03X53150Y565162I0J-1968D01*
G01X161418Y567130D02*
X55118D01*
G01X73426Y652559D02*
G03X69488Y656496I-3937J0D01*
G01X81300Y652559D02*
G03X69488Y664370I-11811J0D01*
G01X55954Y731496D02*
G03X54098Y730184I0J-1969D01*
G01X153544Y731496D02*
X55954D01*
G01X80709Y43307D02*
G03X82677Y41339I1968J0D01*
G01Y47244D02*
G03X80709Y45276I0J-1968D01*
G01X188977Y47244D02*
X82677D01*
G01Y41339D02*
X188977D01*
G01X80709Y45276D02*
Y43307D01*
G01X86614Y101181D02*
G03X82677Y105118I-3937J0D01*
G01X86614Y95276D02*
Y101181D01*
G01X82677Y91339D02*
G03X86614Y95276I0J3937D01*
G01X73426Y267323D02*
G03X77363Y263386I3937J0D01*
G01X73426Y267323D02*
Y282874D01*
G01X77363Y263386D02*
X159449D01*
G01X81300Y271260D02*
Y282874D01*
G01Y271260D02*
X155512D01*
G01Y361811D02*
X74016D01*
G01X80709Y412992D02*
G03X82677Y411024I1968J0D01*
G01Y416929D02*
G03X80709Y414961I0J-1968D01*
G01X188977Y416929D02*
X82677D01*
G01Y411024D02*
X188977D01*
G01X80709Y414961D02*
Y412992D01*
G01X86614Y464961D02*
Y470866D01*
G01X82677Y461024D02*
G03X86614Y464961I0J3937D01*
G01Y470866D02*
G03X82677Y474803I-3937J0D01*
G01X73426Y637008D02*
G03X77363Y633071I3937J0D01*
G01X73426Y637008D02*
Y652559D01*
G01X77363Y633071D02*
X159449D01*
G01X81300Y640945D02*
Y652559D01*
G01Y640945D02*
X155512D01*
G01X109449Y95276D02*
Y101181D01*
G01X113386Y105118D02*
G03X109449Y101181I0J-3937D01*
G01Y95276D02*
G03X113386Y91339I3937J0D01*
G01X109449Y464961D02*
Y470866D01*
G01Y464961D02*
G03X113386Y461024I3937J0D01*
G01Y474803D02*
G03X109449Y470866I0J-3937D01*
G01X161418Y179729D02*
G03X163386Y181697I0J1968D01*
G01Y195477D02*
G03X161418Y197445I-1968J0D01*
G01X159449Y263386D02*
G03X163386Y267323I0J3937D01*
G01X155512Y303937D02*
Y271260D01*
G01X163386Y303937D02*
G03X155512I-3937J0D01*
G01Y329134D02*
G03X163386I3937J0D01*
G01X155512Y361811D02*
Y329134D01*
G01X161418Y549414D02*
G03X163386Y551382I0J1968D01*
G01Y565162D02*
G03X161418Y567130I-1968J0D01*
G01X159449Y633071D02*
G03X163386Y637008I0J3937D01*
G01X155512Y673622D02*
Y640945D01*
G01X163386Y673622D02*
G03X155512I-3937J0D01*
G01Y698819D02*
G03X163386I3937J0D01*
G01X155512Y729528D02*
Y698819D01*
G01Y729528D02*
G03X153544Y731496I-1968J0D01*
G01X163386Y181697D02*
Y195477D01*
G01Y357874D02*
Y267323D01*
G01X167323Y361811D02*
G03X163386Y357874I0J-3937D01*
G01X535433Y361811D02*
X167323D01*
G01X163386Y551382D02*
Y565162D01*
G01Y727559D02*
Y637008D01*
G01X167323Y731496D02*
G03X163386Y727559I0J-3937D01*
G01X535433Y731496D02*
X167323D01*
G01X188977Y41339D02*
G03X190945Y43307I0J1968D01*
G01Y45276D02*
G03X188977Y47244I-1968J0D01*
G01X190945Y43307D02*
Y45276D01*
G01X196851Y97244D02*
G03X194882Y95276I0J-1969D01*
G01X192914Y91339D02*
G03X194882Y93307I0J1968D01*
G01X196851Y97244D02*
X269685D01*
G01X194882Y93307D02*
Y95276D01*
G01X188977Y411024D02*
G03X190945Y412992I0J1968D01*
G01Y414961D02*
G03X188977Y416929I-1968J0D01*
G01X190945Y412992D02*
Y414961D01*
G01X196851Y466929D02*
G03X194882Y464961I-1J-1968D01*
G01X192914Y461024D02*
G03X194882Y462992I0J1968D01*
G01D02*
Y464961D01*
G01X196851Y466929D02*
X269685D01*
G01Y97244D02*
G03X273622Y101181I0J3937D01*
G01Y252756D02*
Y101181D01*
G01X261811Y105118D02*
G03X265748Y109055I0J3937D01*
G01D02*
Y260630D01*
G01X273622Y165551D02*
G03X265748I-3937J0D01*
G01Y196260D02*
G03X273622I3937J0D01*
G01X269685Y264567D02*
G03X265748Y260630I0J-3937D01*
G01X277559Y256693D02*
G03X273622Y252756I0J-3937D01*
G01X342520Y264567D02*
X269685D01*
G01X254331Y361811D02*
G03Y369685I0J3937D01*
G01X261811Y474803D02*
G03X265748Y478740I0J3937D01*
G01D02*
Y630315D01*
G01X269685Y466929D02*
G03X273622Y470866I0J3937D01*
G01Y622441D02*
Y470866D01*
G01Y535236D02*
G03X265748I-3937J0D01*
G01Y565945D02*
G03X273622I3937J0D01*
G01X277559Y626378D02*
G03X273622Y622441I0J-3937D01*
G01X269685Y634252D02*
G03X265748Y630315I0J-3937D01*
G01X342520Y634252D02*
X269685D01*
G01X561024Y256693D02*
X277559D01*
G01X285040Y369685D02*
G03Y361811I0J-3937D01*
G01X561024Y626378D02*
X277559D01*
G01X342520Y264567D02*
G03X344488Y266536I0J1968D01*
G01X342520Y634252D02*
G03X344488Y636221I0J1968D01*
G01X346457Y270473D02*
G03X344488Y268504I0J-1969D01*
G01X346457Y270473D02*
X535433D01*
G01X344488Y268504D02*
Y266536D01*
G01X350394Y320473D02*
G03X348426Y318504I0J-1968D01*
G01Y316536D02*
G03X350394Y314567I1968J-1D01*
G01D02*
X456693D01*
G01Y320473D02*
X350394D01*
G01X348426Y318504D02*
Y316536D01*
G01X346457Y640158D02*
G03X344488Y638189I0J-1969D01*
G01X346457Y640158D02*
X535433D01*
G01X344488Y638189D02*
Y636221D01*
G01X350394Y690158D02*
G03X348426Y688189I0J-1968D01*
G01Y686221D02*
G03X350394Y684252I1968J-1D01*
G01D02*
X456693D01*
G01Y690158D02*
X350394D01*
G01X348426Y688189D02*
Y686221D01*
G01X383859Y1969D02*
G03X385827Y0I1968J-1D01*
G01D02*
X523622D01*
G01X372048D02*
G03X375985Y3937I0J3937D01*
G01X383859Y1969D02*
Y32677D01*
G01X375985Y3937D02*
Y94488D01*
G01X383859Y32677D02*
G03X375985I-3937J0D01*
G01Y57874D02*
G03X383859I3937J0D01*
G01D02*
Y90551D01*
G01X379922Y98425D02*
G03X375985Y94488I0J-3937D01*
G01X458071Y90551D02*
X383859D01*
G01X462008Y98425D02*
X379922D01*
G01X375985Y166334D02*
G03X377953Y164365I1969J0D01*
G01X375985Y180113D02*
Y166334D01*
G01X377953Y164365D02*
X484252D01*
G01X377953Y182082D02*
G03X375985Y180113I0J-1968D01*
G01X484252Y182082D02*
X377953D01*
G01X383859Y369685D02*
X465355D01*
G01X372048D02*
G03X375985Y373622I0J3937D01*
G01X383859Y369685D02*
Y402362D01*
G01X375985Y373622D02*
Y464173D01*
G01X383859Y402362D02*
G03X375985I-3937J0D01*
G01Y427559D02*
G03X383859I3937J0D01*
G01D02*
Y460236D01*
G01X379922Y468110D02*
G03X375985Y464173I0J-3937D01*
G01X458071Y460236D02*
X383859D01*
G01X462008Y468110D02*
X379922D01*
G01X375985Y536019D02*
G03X377953Y534050I1969J0D01*
G01D02*
X484252D01*
G01X377953Y551767D02*
G03X375985Y549799I0J-1968D01*
G01D02*
Y536019D01*
G01X484252Y551767D02*
X377953D01*
G01X429922Y260630D02*
Y266536D01*
G01X425985Y256693D02*
G03X429922Y260630I0J3937D01*
G01Y266536D02*
G03X425985Y270473I-3937J0D01*
G01X429922Y630315D02*
Y636221D01*
G01X425985Y626378D02*
G03X429922Y630315I0J3937D01*
G01Y636221D02*
G03X425985Y640158I-3937J0D01*
G01X452756Y260630D02*
G03X456693Y256693I3937J0D01*
G01X452756Y260630D02*
Y266536D01*
G01X456693Y270473D02*
G03X452756Y266536I0J-3937D01*
G01X458662Y318504D02*
G03X456693Y320473I-1969J0D01*
G01Y314567D02*
G03X458662Y316536I0J1969D01*
G01X452756Y630315D02*
G03X456693Y626378I3937J0D01*
G01X452756Y630315D02*
Y636221D01*
G01X456693Y640158D02*
G03X452756Y636221I0J-3937D01*
G01X458662Y688189D02*
G03X456693Y690158I-1969J0D01*
G01Y684252D02*
G03X458662Y686221I0J1969D01*
G01X458071Y78937D02*
G03X469882Y67126I11811J0D01*
G01X465945Y78937D02*
G03X469882Y75000I3937J0D01*
G01X458071Y90551D02*
Y78937D01*
G01X465945Y94488D02*
Y78937D01*
G01X469882Y67126D02*
X525591D01*
G01X469882Y75000D02*
X529528D01*
G01X465945Y94488D02*
G03X462008Y98425I-3937J0D01*
G01X458662Y316536D02*
Y318504D01*
G01X465355Y361811D02*
G03Y369685I0J3937D01*
G01X458071Y448622D02*
G03X469882Y436811I11811J0D01*
G01D02*
X525591D01*
G01X465945Y448622D02*
G03X469882Y444685I3937J0D01*
G01X465945Y464173D02*
G03X462008Y468110I-3937J0D01*
G01X458071Y460236D02*
Y448622D01*
G01X465945Y464173D02*
Y448622D01*
G01X469882Y444685D02*
X529528D01*
G01X458662Y686221D02*
Y688189D01*
G01X484252Y164365D02*
G03X486221Y166334I0J1969D01*
G01D02*
Y180113D01*
G01D02*
G03X484252Y182082I-1969J0D01*
G01X496063Y369685D02*
G03Y361811I0J-3937D01*
G01Y369685D02*
X525591D01*
G01X484252Y534050D02*
G03X486221Y536019I0J1969D01*
G01Y549799D02*
G03X484252Y551767I-1969J-1D01*
G01X486221Y536019D02*
Y549799D01*
G01X523622Y0D02*
G03X525591Y1969I0J1969D01*
G01X533465Y3937D02*
G03X537402Y0I3937J0D01*
G01X525591Y1969D02*
Y20965D01*
G01X533465Y3937D02*
Y71063D01*
G01X537402Y0D02*
X561024D01*
G01X533465Y20965D02*
G03X525591I-3937J0D01*
G01Y46162D02*
G03X533465I3937J0D01*
G01X525591D02*
Y67126D01*
G01X533465Y71063D02*
G03X529528Y75000I-3937J0D01*
G01X535433Y270473D02*
G03X539370Y274410I0J3937D01*
G01D02*
Y357874D01*
G01X547244Y270473D02*
X562992D01*
G01X547244D02*
Y303543D01*
G01D02*
G03X539370I-3937J0D01*
G01Y328740D02*
G03X547244I3937J0D01*
G01D02*
Y361811D01*
G01X539370Y357874D02*
G03X535433Y361811I-3937J0D01*
G01X547244D02*
X562992D01*
G01X533465Y373622D02*
G03X537402Y369685I3937J0D01*
G01X525591D02*
Y390650D01*
G01X533465Y373622D02*
Y440748D01*
G01X537402Y369685D02*
X561024D01*
G01X533465Y390650D02*
G03X525591I-3937J0D01*
G01Y415847D02*
G03X533465I3937J0D01*
G01X525591D02*
Y436811D01*
G01X533465Y440748D02*
G03X529528Y444685I-3937J0D01*
G01X535433Y640158D02*
G03X539370Y644095I0J3937D01*
G01D02*
Y727559D01*
G01X547244Y640158D02*
X562992D01*
G01X547244D02*
Y673228D01*
G01D02*
G03X539370I-3937J0D01*
G01Y698425D02*
G03X547244I3937J0D01*
G01D02*
Y727559D01*
G01X551181Y731496D02*
G03X547244Y727559I0J-3937D01*
G01X539370D02*
G03X535433Y731496I-3937J0D01*
G01X561024Y0D02*
G03X564961Y3937I0J3937D01*
G01D02*
Y252756D01*
G01D02*
G03X561024Y256693I-3937J0D01*
G01X562992Y270473D02*
G03X564961Y272441I1J1968D01*
G01D02*
Y359843D01*
G01D02*
G03X562992Y361811I-1968J0D01*
G01X561024Y369685D02*
G03X564961Y373622I0J3937D01*
G01D02*
Y622441D01*
G01D02*
G03X561024Y626378I-3937J0D01*
G01X562992Y640158D02*
G03X564961Y642126I1J1968D01*
G01D02*
Y721654D01*
G01D02*
G03X555118Y731496I-9842J0D01*
G01X551181D02*
X555118D01*
G54D12*
G01X111786Y13194D02*
X112695Y14306D01*
G01X110046Y11798D02*
Y13815D01*
G01X111786Y11540D02*
Y13194D01*
G01D02*
X112695Y14306D01*
G01X111786Y11540D02*
Y13194D01*
G01X110046Y11798D02*
Y13815D01*
G01X111739Y15888D02*
X120749Y17721D01*
G01X116722Y15126D02*
X120749Y15945D01*
G01X116723Y15126D02*
X116722D01*
G01X112695Y14306D02*
X116723Y15126D01*
G01X110046Y13815D02*
X111739Y15888D01*
G01X116722Y15126D02*
X120749Y15945D01*
G01X111739Y15888D02*
X120749Y17721D01*
G01X116723Y15126D02*
X116722D01*
G01X111739Y15888D02*
X120749Y17721D01*
G01X112695Y14306D02*
X116723Y15126D01*
G01X111739Y15888D02*
X120749Y17721D01*
G01X110046Y13815D02*
X111739Y15888D01*
G01X109917Y58069D02*
X111404Y60308D01*
G01X111657Y57543D02*
X112456Y58746D01*
G01X109917Y56158D02*
Y58069D01*
G01X111657Y56158D02*
Y57543D01*
G01D02*
X112456Y58746D01*
G01X109917Y58069D02*
X111404Y60308D01*
G01X111657Y56158D02*
Y57543D01*
G01X109917Y56158D02*
Y58069D01*
G01X111404Y60308D02*
X123676Y62805D01*
G01X112456Y58746D02*
X123676Y61029D01*
G01X112456Y58746D02*
X123676Y61029D01*
G01X111404Y60308D02*
X123676Y62805D01*
G01X131189Y15597D02*
X170994Y23696D01*
G01X137892Y15185D02*
X140361Y15687D01*
G01X131189Y13821D02*
X133658Y14322D01*
G01X120749Y17721D02*
X131189Y15597D01*
G01X120749Y15945D02*
X131189Y13821D01*
G01Y15597D02*
X170994Y23696D01*
G01X131189Y15597D02*
X170994Y23696D01*
G01X131189Y15597D02*
X170994Y23696D01*
G01X137892Y15185D02*
X140361Y15687D01*
G01X131189Y15597D02*
X170994Y23696D01*
G01X131189Y13821D02*
X133658Y14322D01*
G01X131189Y15597D02*
X170994Y23696D01*
G01X120749Y15945D02*
X131189Y13821D01*
G01X120749Y17721D02*
X131189Y15597D01*
G01X135582Y60383D02*
X184311Y70297D01*
G01X135582Y58607D02*
X138051Y59109D01*
G01X123676Y62805D02*
X135582Y60383D01*
G01X123676Y61029D02*
X135582Y58607D01*
G01Y60383D02*
X184311Y70297D01*
G01X135582Y60383D02*
X184311Y70297D01*
G01X135582Y60383D02*
X184311Y70297D01*
G01X135582Y60383D02*
X184311Y70297D01*
G01X135582Y58607D02*
X138051Y59109D01*
G01X135582Y60383D02*
X184311Y70297D01*
G01X123676Y61029D02*
X135582Y58607D01*
G01X123676Y62805D02*
X135582Y60383D01*
G01X158000Y19276D02*
X171672Y22058D01*
G01X151298Y17913D02*
X153767Y18415D01*
G01X144595Y16549D02*
X147064Y17051D01*
G01X158000Y19276D02*
X171672Y22058D01*
G01X151298Y17913D02*
X153767Y18415D01*
G01X144595Y16549D02*
X147064Y17051D01*
G01X162394Y64062D02*
X184311Y68521D01*
G01X155691Y62699D02*
X158160Y63201D01*
G01X148988Y61335D02*
X151457Y61837D01*
G01X142285Y59971D02*
X144754Y60473D01*
G01X162394Y64062D02*
X184311Y68521D01*
G01X155691Y62699D02*
X158160Y63201D01*
G01X148988Y61335D02*
X151457Y61837D01*
G01X142285Y59971D02*
X144754Y60473D01*
G01X170994Y23696D02*
X201984Y44207D01*
G01X171672Y22058D02*
X202662Y42569D01*
G01X171672Y22058D02*
X202662Y42569D01*
G01X170994Y23696D02*
X201984Y44207D01*
G01X184311Y70297D02*
X211996Y64666D01*
G01X184311Y68521D02*
X211996Y62890D01*
G01X184311Y68521D02*
X211996Y62890D01*
G01X184311Y70297D02*
X211996Y64666D01*
G01X201984Y44207D02*
X236393Y51211D01*
G01X202662Y42569D02*
X237071Y49573D01*
G01X202662Y42569D02*
X237071Y49573D01*
G01X201984Y44207D02*
X236393Y51211D01*
G01X211996Y64666D02*
X250023Y72403D01*
G01X211996Y62890D02*
X250701Y70765D01*
G01X211996Y62890D02*
X250701Y70765D01*
G01X211996Y64666D02*
X250023Y72403D01*
G01X236393Y51211D02*
X285135Y83472D01*
G01X237071Y49573D02*
X286391Y82216D01*
G01X237071Y49573D02*
X286391Y82216D01*
G01X236393Y51211D02*
X285135Y83472D01*
G01X250023Y72403D02*
X281646Y93331D01*
G01X250701Y70765D02*
X282902Y92075D01*
G01X250701Y70765D02*
X282902Y92075D01*
G01X250023Y72403D02*
X281646Y93331D01*
G01X297537Y102290D02*
X300539Y100304D01*
G01X297896Y104139D02*
X301497Y101757D01*
G01X297537Y102290D02*
X300539Y100304D01*
G01X291054Y102747D02*
X297896Y104139D01*
G01X291756Y101114D02*
X297537Y102290D01*
G01X285136Y98603D02*
X291054Y102747D01*
G01X286405Y97367D02*
X291756Y101114D01*
G01X281646Y93331D02*
X285136Y98603D01*
G01X282902Y92075D02*
X286405Y97367D01*
G01X297537Y102290D02*
X300539Y100304D01*
G01X297896Y104139D02*
X301497Y101757D01*
G01X291756Y101114D02*
X297537Y102290D01*
G01X291054Y102747D02*
X297896Y104139D01*
G01X286405Y97367D02*
X291756Y101114D01*
G01X285136Y98603D02*
X291054Y102747D01*
G01X282902Y92075D02*
X286405Y97367D01*
G01X281646Y93331D02*
X285136Y98603D01*
G01X293769Y95181D02*
X295384D01*
G01X294318Y93441D02*
X295470D01*
G01X292121Y94026D02*
X293769Y95181D01*
G01X293391Y92791D02*
X294318Y93440D01*
G01X285135Y83472D02*
X292121Y94026D01*
G01X286391Y82216D02*
X293391Y92790D01*
G01X294318Y93441D02*
X295470D01*
G01X293769Y95181D02*
X295384D01*
G01X293391Y92791D02*
X294318Y93440D01*
G01X292121Y94026D02*
X293769Y95181D01*
G01X286391Y82216D02*
X293391Y92790D01*
G01X285135Y83472D02*
X292121Y94026D01*
G01X301686Y77594D02*
Y83948D01*
G01X303426Y77770D02*
Y84669D01*
G01X302744Y72397D02*
X301686Y77594D01*
G01X304306Y73451D02*
X303426Y77770D01*
G01X306842Y69683D02*
X302744Y72397D01*
G01X307202Y71532D02*
X304306Y73451D01*
G01X313229Y70983D02*
X306842Y69683D01*
G01X313229Y72759D02*
X307202Y71532D01*
G01X318659Y69878D02*
X313229Y70983D01*
G01X318659Y71654D02*
X313229Y72759D01*
G01X326866Y71548D02*
X318659Y69878D01*
G01X326866Y73324D02*
X318659Y71654D01*
G01X303426Y77770D02*
Y84669D01*
G01X301686Y77594D02*
Y83948D01*
G01X304306Y73451D02*
X303426Y77770D01*
G01X302744Y72397D02*
X301686Y77594D01*
G01X307202Y71532D02*
X304306Y73451D01*
G01X306842Y69683D02*
X302744Y72397D01*
G01X313229Y72759D02*
X307202Y71532D01*
G01X313229Y70983D02*
X306842Y69683D01*
G01X318659Y71654D02*
X313229Y72759D01*
G01X318659Y69878D02*
X313229Y70983D01*
G01X326866Y73324D02*
X318659Y71654D01*
G01X326866Y71548D02*
X318659Y69878D01*
G01X312597Y84562D02*
X310791D01*
G01X312421Y86302D02*
X310859D01*
G01X315274Y85106D02*
X312597Y84562D01*
G01X314220Y86668D02*
X312421Y86302D01*
G01X317463Y88416D02*
X315274Y85106D01*
G01X315614Y88775D02*
X314220Y86668D01*
G01X316227Y94494D02*
X317463Y88416D01*
G01X314451Y94494D02*
X315614Y88775D01*
G01X317706Y101762D02*
X316227Y94494D01*
G01X316068Y102440D02*
X314451Y94494D01*
G01X374338Y187325D02*
X317706Y101762D01*
G01X317459Y104541D02*
X316068Y102440D01*
G01X312421Y86302D02*
X310859D01*
G01X312597Y84562D02*
X310791D01*
G01X314220Y86668D02*
X312421Y86302D01*
G01X315274Y85106D02*
X312597Y84562D01*
G01X315614Y88775D02*
X314220Y86668D01*
G01X317463Y88416D02*
X315274Y85106D01*
G01X314451Y94494D02*
X315614Y88775D01*
G01X316227Y94494D02*
X317463Y88416D01*
G01X316068Y102440D02*
X314451Y94494D01*
G01X317706Y101762D02*
X316227Y94494D01*
G01X317459Y104541D02*
X316068Y102440D01*
G01X374338Y187325D02*
X317706Y101762D01*
G01X374338Y187325D02*
X317706Y101762D01*
G01X374338Y187325D02*
X317706Y101762D01*
G01X300846Y84788D02*
X299844D01*
G01X301567Y86528D02*
X299664D01*
G01X303426Y84669D02*
X301567Y86528D01*
G01X301686Y83948D02*
X300846Y84788D01*
G01X303426Y84669D02*
X301567Y86528D01*
G01D02*
X299664D01*
G01X300846Y84788D02*
X299844D01*
G01X303426Y84669D02*
X301567Y86528D01*
G01X300846Y84788D02*
X299844D01*
G01X301686Y83948D02*
X300846Y84788D01*
G01X305111Y95026D02*
X306065D01*
G01X304390Y93286D02*
X306339D01*
G01X302531Y95145D02*
X304390Y93286D01*
G01X304271Y95866D02*
X305111Y95026D01*
G01X302531Y95145D02*
X304390Y93286D01*
G01X304271Y99033D02*
Y95866D01*
G01X302531Y98312D02*
Y95145D01*
G01X301643Y101661D02*
X304271Y99033D01*
G01X300539Y100304D02*
X302531Y98312D01*
G01X301497Y101757D02*
X301643Y101661D01*
G01X304390Y93286D02*
X306339D01*
G01X305111Y95026D02*
X306065D01*
G01X302531Y95145D02*
X304390Y93286D01*
G01X305111Y95026D02*
X306065D01*
G01X304271Y95866D02*
X305111Y95026D01*
G01X302531Y98312D02*
Y95145D01*
G01X304271Y99033D02*
Y95866D01*
G01X300539Y100304D02*
X302531Y98312D01*
G01X301643Y101661D02*
X304271Y99033D01*
G01X301497Y101757D02*
X301643Y101661D01*
G01X321234Y110245D02*
X319843Y108144D01*
G01X321234Y110245D02*
X319843Y108144D01*
G01X331809Y70542D02*
X326866Y71548D01*
G01X331809Y72318D02*
X326866Y73324D01*
G01X340821Y72375D02*
X331809Y70542D01*
G01X340132Y74011D02*
X331809Y72318D01*
G01X349689Y78395D02*
X340821Y72375D01*
G01X348427Y79642D02*
X340132Y74011D01*
G01X331809Y72318D02*
X326866Y73324D01*
G01X331809Y70542D02*
X326866Y71548D01*
G01X340132Y74011D02*
X331809Y72318D01*
G01X340821Y72375D02*
X331809Y70542D01*
G01X348427Y79642D02*
X340132Y74011D01*
G01X349689Y78395D02*
X340821Y72375D01*
G01X326415Y93553D02*
X324484D01*
G01X325694Y95293D02*
X324506D01*
G01X328274Y95412D02*
X326415Y93553D01*
G01X326534Y96133D02*
X325694Y95293D01*
G01X328274Y100085D02*
Y95412D01*
G01X326534Y100085D02*
Y96133D01*
G01X339744Y93441D02*
X335112D01*
G01X339744Y95181D02*
X335028D01*
G01X325984Y84464D02*
X324383D01*
G01X325984Y86204D02*
X324557D01*
G01X341898Y84577D02*
X334983D01*
G01X341898Y86317D02*
X335308D01*
G01X325694Y95293D02*
X324506D01*
G01X326415Y93553D02*
X324484D01*
G01X326534Y96133D02*
X325694Y95293D01*
G01X328274Y95412D02*
X326415Y93553D01*
G01X326534Y100085D02*
Y96133D01*
G01X328274Y100085D02*
Y95412D01*
G01X339744Y95181D02*
X335028D01*
G01X339744Y93441D02*
X335112D01*
G01X325984Y86204D02*
X324557D01*
G01X325984Y84464D02*
X324383D01*
G01X341898Y86317D02*
X335308D01*
G01X341898Y84577D02*
X334983D01*
G01X373082Y188581D02*
X323618Y113848D01*
G01X373082Y188581D02*
X323618Y113848D01*
G01X369060Y107662D02*
X349689Y78395D01*
G01X349818Y81743D02*
X348427Y79642D01*
G01X349818Y81743D02*
X348427Y79642D01*
G01X369060Y107662D02*
X349689Y78395D01*
G01X369060Y107662D02*
X349689Y78395D01*
G01X369060Y107662D02*
X349689Y78395D01*
G01X369060Y107662D02*
X349689Y78395D01*
G01X369060Y107662D02*
X349689Y78395D01*
G01X353593Y87447D02*
X352202Y85346D01*
G01X357368Y93151D02*
X355977Y91050D01*
G01X361143Y98855D02*
X359752Y96754D01*
G01X367804Y108918D02*
X363528Y102458D01*
G01X353593Y87447D02*
X352202Y85346D01*
G01X357368Y93151D02*
X355977Y91050D01*
G01X361143Y98855D02*
X359752Y96754D01*
G01X367804Y108918D02*
X363528Y102458D01*
G01X399914Y128085D02*
X369060Y107662D01*
G01X383229Y119129D02*
X367804Y108918D01*
G01X398658Y129341D02*
X383230Y119128D01*
G01X383229Y119129D02*
X367804Y108918D01*
G01X399914Y128085D02*
X369060Y107662D01*
G01X398658Y129341D02*
X383230Y119128D01*
G01X399914Y128085D02*
X369060Y107662D01*
G01X380474Y191386D02*
X374338Y187325D01*
G01X379796Y193024D02*
X373082Y188581D01*
G01X399769Y195311D02*
X380474Y191386D01*
G01X385309Y194146D02*
X379796Y193024D01*
G01D02*
X373082Y188581D01*
G01X380474Y191386D02*
X374338Y187325D01*
G01X385309Y194146D02*
X379796Y193024D01*
G01X399769Y195311D02*
X380474Y191386D01*
G01X399769Y195311D02*
X380474Y191386D01*
G01X399769Y195311D02*
X380474Y191386D01*
G01X392012Y195509D02*
X389543Y195007D01*
G01X392012Y195509D02*
X389543Y195007D01*
G01X401942Y131148D02*
X399914Y128085D01*
G01X400304Y131826D02*
X398658Y129341D01*
G01X402710Y134922D02*
X401942Y131148D01*
G01X400970Y135098D02*
X400304Y131826D01*
G01X402710Y136371D02*
Y134922D01*
G01X400970Y136353D02*
Y135098D01*
G01X400304Y131826D02*
X398658Y129341D01*
G01X401942Y131148D02*
X399914Y128085D01*
G01X400970Y135098D02*
X400304Y131826D01*
G01X402710Y134922D02*
X401942Y131148D01*
G01X400970Y136353D02*
Y135098D01*
G01X402710Y136371D02*
Y134922D01*
G01X398715Y196873D02*
X396246Y196371D01*
G01X402701Y199741D02*
X399769Y195311D01*
G01X400961Y200266D02*
X398715Y196873D01*
G01X402701Y202110D02*
Y199741D01*
G01X400961Y202110D02*
Y200266D01*
G01X398715Y196873D02*
X396246Y196371D01*
G01X400961Y200266D02*
X398715Y196873D01*
G01X402701Y199741D02*
X399769Y195311D01*
G01X400961Y202110D02*
Y200266D01*
G01X402701Y202110D02*
Y199741D01*
M02*
